# S9S_MB_2U (Grand Teton) — schematic netlist excerpt (pin names and nets, part order shuffled) for the footprints in the layout excerpt that follows; sources: Cadence DE-HDL packaged netlist, KiCad conversion of 03242023_DA0F0TMBIJ0_F0T_Motherboard_J_brd_V01_OCP.brd

R708  Q_RES  10K 1% EMPTY  pkg 0402LF  page 129 : A = RST_PLD_CPU0_DRAM_EF_N ; B = GND
C32  Q_CAP  2.2UF 6.3V 20% X6S  pkg C0402  page 92 : A = P3V3_AUX ; B = GND

(kicad_pcb
	(version 20260206)
	(generator "pcbnew")
	(generator_version "10.0")
	(general
		(thickness 1.6)
		(legacy_teardrops no)
	)
	(paper "A4")
	(title_block
		(title "03242023_DA0F0TMBIJ0_F0T_Motherboard_J_brd_V01_OCP.brd")
		(comment 1 "Grand Teton / footprints 5804-5805 of 6105")
	)
	(layers
		(0 "F.Cu" signal "TOP")
		(4 "In1.Cu" signal "GND")
		(6 "In2.Cu" signal "IN1")
		(8 "In3.Cu" signal "GND1")
		(10 "In4.Cu" signal "IN2")
		(12 "In5.Cu" signal "GND2")
		(14 "In6.Cu" signal "IN3")
		(16 "In7.Cu" signal "GND3")
		(18 "In8.Cu" signal "VCC")
		(20 "In9.Cu" signal "VCC1")
		(22 "In10.Cu" signal "GND4")
		(24 "In11.Cu" signal "IN4")
		(26 "In12.Cu" signal "GND5")
		(28 "In13.Cu" signal "IN5")
		(30 "In14.Cu" signal "GND6")
		(32 "In15.Cu" signal "IN6")
		(34 "In16.Cu" signal "GND7")
		(2 "B.Cu" signal "BOTTOM")
		(9 "F.Adhes" user "F.Adhesive")
		(11 "B.Adhes" user "B.Adhesive")
		(13 "F.Paste" user "Package Geometry/Pastemask Top")
		(15 "B.Paste" user "Package Geometry/Pastemask Bottom")
		(5 "F.SilkS" user "Ref Des/Silkscreen Top")
		(7 "B.SilkS" user "Ref Des/Silkscreen Bottom")
		(1 "F.Mask" user "Board Geometry/Soldermask Top")
		(3 "B.Mask" user "Board Geometry/Soldermask Bottom")
		(17 "Dwgs.User" user "User.Drawings")
		(19 "Cmts.User" user "User.Comments")
		(21 "Eco1.User" user "User.Eco1")
		(23 "Eco2.User" user "User.Eco2")
		(25 "Edge.Cuts" user "Board Geometry/Outline")
		(27 "Margin" user)
		(31 "F.CrtYd" user "Package Geometry/Place Bound Top")
		(29 "B.CrtYd" user "Package Geometry/Place Bound Bottom")
		(35 "F.Fab" user "Ref Des/Assembly Top")
		(33 "B.Fab" user "Ref Des/Assembly Bottom")
	)
	(footprint ""
		(layer "B.Cu")
		(at 429.397414 -319.263776 180)
		(property "Reference" "C32"
			(at 0 0 0)
			(layer "B.SilkS")
			(hide yes)
			(effects
				(font
					(size 1.27 1.27)
				)
				(justify mirror)
			)
		)
		(property "Value" ""
			(at 0 0 0)
			(layer "B.Fab")
			(effects
				(font
					(size 1.27 1.27)
				)
				(justify mirror)
			)
		)
		(duplicate_pad_numbers_are_jumpers no)
		(fp_line
			(start 0.7874 0.4064)
			(end 0.7874 -0.4064)
			(stroke
				(width 0.1524)
				(type default)
			)
			(layer "B.SilkS")
		)
		(fp_line
			(start 0.7874 -0.4064)
			(end -0.7874 -0.4064)
			(stroke
				(width 0.1524)
				(type default)
			)
			(layer "B.SilkS")
		)
		(fp_line
			(start -0.7874 0.4064)
			(end 0.7874 0.4064)
			(stroke
				(width 0.1524)
				(type default)
			)
			(layer "B.SilkS")
		)
		(fp_line
			(start -0.7874 -0.4064)
			(end -0.7874 0.4064)
			(stroke
				(width 0.1524)
				(type default)
			)
			(layer "B.SilkS")
		)
		(fp_line
			(start 0.67945 0.3048)
			(end 0.67945 -0.305054)
			(stroke
				(width 0.1)
				(type default)
			)
			(layer "B.Fab")
		)
		(fp_line
			(start 0.67945 -0.305054)
			(end 0.12065 -0.305054)
			(stroke
				(width 0.1)
				(type default)
			)
			(layer "B.Fab")
		)
		(fp_line
			(start 0.12065 0.3048)
			(end 0.67945 0.3048)
			(stroke
				(width 0.1)
				(type default)
			)
			(layer "B.Fab")
		)
		(fp_line
			(start 0.12065 0.2794)
			(end 0.12065 0.3048)
			(stroke
				(width 0.1)
				(type default)
			)
			(layer "B.Fab")
		)
		(fp_line
			(start 0.12065 -0.2794)
			(end -0.12065 -0.2794)
			(stroke
				(width 0.1)
				(type default)
			)
			(layer "B.Fab")
		)
		(fp_line
			(start 0.12065 -0.305054)
			(end 0.12065 -0.2794)
			(stroke
				(width 0.1)
				(type default)
			)
			(layer "B.Fab")
		)
		(fp_line
			(start -0.120396 0.3048)
			(end -0.120396 0.2794)
			(stroke
				(width 0.1)
				(type default)
			)
			(layer "B.Fab")
		)
		(fp_line
			(start -0.120396 0.2794)
			(end 0.12065 0.2794)
			(stroke
				(width 0.1)
				(type default)
			)
			(layer "B.Fab")
		)
		(fp_line
			(start -0.12065 -0.2794)
			(end -0.12065 -0.3048)
			(stroke
				(width 0.1)
				(type default)
			)
			(layer "B.Fab")
		)
		(fp_line
			(start -0.12065 -0.3048)
			(end -0.67945 -0.3048)
			(stroke
				(width 0.1)
				(type default)
			)
			(layer "B.Fab")
		)
		(fp_line
			(start -0.67945 0.3048)
			(end -0.120396 0.3048)
			(stroke
				(width 0.1)
				(type default)
			)
			(layer "B.Fab")
		)
		(fp_line
			(start -0.67945 -0.3048)
			(end -0.67945 0.3048)
			(stroke
				(width 0.1)
				(type default)
			)
			(layer "B.Fab")
		)
		(pad "1" smd circle
			(at 0.40005 0)
			(size 0 0)
			(layers "B.Cu" "B.Mask" "B.Paste")
			(net "P3V3_AUX")
		)
		(pad "2" smd circle
			(at -0.40005 0)
			(size 0 0)
			(layers "B.Cu" "B.Mask" "B.Paste")
			(net "GND")
		)
	)
	(footprint ""
		(layer "B.Cu")
		(at 420.285418 -193.353436 -90)
		(property "Reference" "R708"
			(at 0 0 90)
			(layer "B.SilkS")
			(hide yes)
			(effects
				(font
					(size 1.27 1.27)
				)
				(justify mirror)
			)
		)
		(property "Value" ""
			(at 0 0 90)
			(layer "B.Fab")
			(effects
				(font
					(size 1.27 1.27)
				)
				(justify mirror)
			)
		)
		(duplicate_pad_numbers_are_jumpers no)
		(fp_line
			(start -0.7874 0.4064)
			(end 0.7874 0.4064)
			(stroke
				(width 0.1524)
				(type default)
			)
			(layer "B.SilkS")
		)
		(fp_line
			(start 0.7874 0.4064)
			(end 0.7874 -0.4064)
			(stroke
				(width 0.1524)
				(type default)
			)
			(layer "B.SilkS")
		)
		(fp_line
			(start -0.7874 -0.4064)
			(end -0.7874 0.4064)
			(stroke
				(width 0.1524)
				(type default)
			)
			(layer "B.SilkS")
		)
		(fp_line
			(start 0.7874 -0.4064)
			(end -0.7874 -0.4064)
			(stroke
				(width 0.1524)
				(type default)
			)
			(layer "B.SilkS")
		)
		(fp_line
			(start -0.67945 0.3048)
			(end -0.120396 0.3048)
			(stroke
				(width 0.1)
				(type default)
			)
			(layer "B.Fab")
		)
		(fp_line
			(start -0.120396 0.3048)
			(end -0.120396 0.2794)
			(stroke
				(width 0.1)
				(type default)
			)
			(layer "B.Fab")
		)
		(fp_line
			(start 0.12065 0.3048)
			(end 0.67945 0.3048)
			(stroke
				(width 0.1)
				(type default)
			)
			(layer "B.Fab")
		)
		(fp_line
			(start 0.67945 0.3048)
			(end 0.67945 -0.305054)
			(stroke
				(width 0.1)
				(type default)
			)
			(layer "B.Fab")
		)
		(fp_line
			(start -0.120396 0.2794)
			(end 0.12065 0.2794)
			(stroke
				(width 0.1)
				(type default)
			)
			(layer "B.Fab")
		)
		(fp_line
			(start 0.12065 0.2794)
			(end 0.12065 0.3048)
			(stroke
				(width 0.1)
				(type default)
			)
			(layer "B.Fab")
		)
		(fp_line
			(start -0.12065 -0.2794)
			(end -0.12065 -0.3048)
			(stroke
				(width 0.1)
				(type default)
			)
			(layer "B.Fab")
		)
		(fp_line
			(start 0.12065 -0.2794)
			(end -0.12065 -0.2794)
			(stroke
				(width 0.1)
				(type default)
			)
			(layer "B.Fab")
		)
		(fp_line
			(start -0.67945 -0.3048)
			(end -0.67945 0.3048)
			(stroke
				(width 0.1)
				(type default)
			)
			(layer "B.Fab")
		)
		(fp_line
			(start -0.12065 -0.3048)
			(end -0.67945 -0.3048)
			(stroke
				(width 0.1)
				(type default)
			)
			(layer "B.Fab")
		)
		(fp_line
			(start 0.12065 -0.305054)
			(end 0.12065 -0.2794)
			(stroke
				(width 0.1)
				(type default)
			)
			(layer "B.Fab")
		)
		(fp_line
			(start 0.67945 -0.305054)
			(end 0.12065 -0.305054)
			(stroke
				(width 0.1)
				(type default)
			)
			(layer "B.Fab")
		)
		(pad "1" smd circle
			(at 0.40005 0 90)
			(size 0 0)
			(layers "B.Cu" "B.Mask" "B.Paste")
			(net "RST_PLD_CPU0_DRAM_EF_N")
		)
		(pad "2" smd circle
			(at -0.40005 0 90)
			(size 0 0)
			(layers "B.Cu" "B.Mask" "B.Paste")
			(net "GND")
		)
	)
)
